#ISCELL
  mstr_symbols intel_corp_bpage *
  *
#ISCELL
  mstr_standard offpage *
  page245_i1
#ISCELL
  mstr_standard tap *
  page245_i10
#ISCELL
  mstr_standard tap *
  page245_i11
#ISCELL
  mstr_standard tap *
  page245_i12
#ISCELL
  mstr_standard tap *
  page245_i13
#ISCELL
  mstr_standard tap *
  page245_i14
#ISCELL
  mstr_standard tap *
  page245_i15
#ISCELL
  mstr_standard tap *
  page245_i16
#ISCELL
  mstr_standard tap *
  page245_i17
#ISCELL
  mstr_standard tap *
  page245_i18
#ISCELL
  mstr_symbols gnd *
  page245_i19
#ISCELL
  mstr_standard offpage *
  page245_i2
#ISCELL
  mstr_symbols gnd *
  page245_i20
#ISCELL
  mstr_standard offpage *
  page245_i21
#ISCELL
  mstr_standard offpage *
  page245_i22
#ISCELL
  mstr_standard tap *
  page245_i23
#ISCELL
  mstr_standard tap *
  page245_i24
#ISCELL
  mstr_symbols gnd *
  page245_i25
#ISCELL
  mstr_symbols gnd *
  page245_i26
#ISCELL
  mstr_symbols gnd *
  page245_i27
#ISCELL
  mstr_standard offpage *
  page245_i28
#ISCELL
  mstr_standard tap *
  page245_i29
#ISCELL
  mstr_standard offpage *
  page245_i3
#ISCELL
  mstr_standard tap *
  page245_i30
#ISCELL
  mstr_standard tap *
  page245_i31
#ISCELL
  mstr_standard tap *
  page245_i32
#ISCELL
  mstr_standard tap *
  page245_i33
#ISCELL
  mstr_standard tap *
  page245_i34
#ISCELL
  mstr_standard tap *
  page245_i35
#ISCELL
  mstr_standard tap *
  page245_i36
#ISCELL
  mstr_standard tap *
  page245_i37
#ISCELL
  mstr_standard tap *
  page245_i38
#ISCELL
  mstr_standard tap *
  page245_i39
#ISCELL
  mstr_standard offpage *
  page245_i4
#ISCELL
  mstr_standard tap *
  page245_i40
#ISCELL
  mstr_standard tap *
  page245_i41
#ISCELL
  mstr_standard tap *
  page245_i42
#ISCELL
  mstr_standard tap *
  page245_i43
#ISCELL
  mstr_standard tap *
  page245_i44
#ISCELL
  mstr_standard offpage *
  page245_i45
#ISCELL
  mstr_standard offpage *
  page245_i46
#ISCELL
  mstr_standard offpage *
  page245_i47
#CELL
  w_hdl smc-conn60a-22-gp *
  page245_i48
#ISCELL
  mstr_standard tap *
  page245_i5
#ISCELL
  mstr_standard tap *
  page245_i6
#ISCELL
  mstr_standard tap *
  page245_i7
#ISCELL
  mstr_standard tap *
  page245_i8
#ISCELL
  mstr_standard tap *
  page245_i9
